(kicad_pcb
	(version 20240108)
	(generator "pcbnew")
	(generator_version "8.0")
	(general
		(thickness 1.62)
		(legacy_teardrops no)
	)
	(paper "A4")
	(title_block
		(title "Jetson Orin Baseboard")
		(date "2025-03-12")
		(rev "1.3.4")
		(company "Antmicro Ltd")
		(comment 1 "www.antmicro.com")
		(comment 9 "footprints 144-146 of 677")
	)
	(layers
		(0 "F.Cu" signal)
		(1 "In1.Cu" signal)
		(2 "In2.Cu" signal)
		(3 "In3.Cu" signal)
		(4 "In4.Cu" jumper)
		(5 "In5.Cu" signal)
		(6 "In6.Cu" signal)
		(31 "B.Cu" signal)
		(32 "B.Adhes" user "B.Adhesive")
		(33 "F.Adhes" user "F.Adhesive")
		(34 "B.Paste" user)
		(35 "F.Paste" user)
		(36 "B.SilkS" user "B.Silkscreen")
		(37 "F.SilkS" user "F.Silkscreen")
		(38 "B.Mask" user)
		(39 "F.Mask" user)
		(40 "Dwgs.User" user "User.Drawings")
		(41 "Cmts.User" user "User.Comments")
		(42 "Eco1.User" user "User.Eco1")
		(43 "Eco2.User" user "User.Eco2")
		(44 "Edge.Cuts" user)
		(45 "Margin" user)
		(46 "B.CrtYd" user "B.Courtyard")
		(47 "F.CrtYd" user "F.Courtyard")
		(48 "B.Fab" user)
		(49 "F.Fab" user)
	)
	(footprint "antmicro-footprints:LED_0603_1608Metric_G"
		(layer "F.Cu")
		(at 132.8 127.2 -90)
		(descr "LED SMD 0603 Green")
		(tags "LED SMD 0603 Green")
		(property "Reference" "D27"
			(at -1.2 0.5 90)
			(layer "F.SilkS")
			(effects
				(font
					(size 0.7 0.7)
					(thickness 0.15)
				)
				(justify right bottom)
			)
		)
		(property "Value" "LED_G_0603_LTST-C190GKT"
			(at -0.001 1.599 90)
			(layer "F.Fab")
			(effects
				(font
					(size 0.7 0.7)
					(thickness 0.15)
				)
				(justify right bottom)
			)
		)
		(property "Footprint" "antmicro-footprints:LED_0603_1608Metric_G"
			(at 0 0 -90)
			(layer "F.Fab")
			(hide yes)
			(effects
				(font
					(size 1.27 1.27)
					(thickness 0.15)
				)
			)
		)
		(property "Datasheet" "https://media.digikey.com/pdf/Data%20Sheets/Lite-On%20PDFs/LTST-C190GKT.pdf"
			(at 0 0 -90)
			(layer "F.Fab")
			(hide yes)
			(effects
				(font
					(size 1.27 1.27)
					(thickness 0.15)
				)
			)
		)
		(property "Author" "Antmicro"
			(at 5.6 260 0)
			(layer "F.Fab")
			(hide yes)
			(effects
				(font
					(size 1 1)
					(thickness 0.15)
				)
			)
		)
		(property "Color" "Green"
			(at 5.6 260 0)
			(layer "F.Fab")
			(hide yes)
			(effects
				(font
					(size 1 1)
					(thickness 0.15)
				)
			)
		)
		(property "License" "Apache-2.0"
			(at 5.6 260 0)
			(layer "F.Fab")
			(hide yes)
			(effects
				(font
					(size 1 1)
					(thickness 0.15)
				)
			)
		)
		(property "MPN" "LTST-C190GKT"
			(at 5.6 260 0)
			(layer "F.Fab")
			(hide yes)
			(effects
				(font
					(size 1 1)
					(thickness 0.15)
				)
			)
		)
		(property "Manufacturer" "Lite-On"
			(at 5.6 260 0)
			(layer "F.Fab")
			(hide yes)
			(effects
				(font
					(size 1 1)
					(thickness 0.15)
				)
			)
		)
		(sheetname "Peripherals")
		(sheetfile "peripherals.kicad_sch")
		(attr smd)
		(fp_line
			(start 0.22 0.35)
			(end -0.22 0.35)
			(stroke
				(width 0.15)
				(type solid)
			)
			(layer "F.SilkS")
		)
		(fp_line
			(start -0.094672 0.201008)
			(end -0.094672 -0.198992)
			(stroke
				(width 0.1)
				(type solid)
			)
			(layer "F.SilkS")
		)
		(fp_line
			(start 0.105328 0.201008)
			(end -0.094672 0.001008)
			(stroke
				(width 0.1)
				(type solid)
			)
			(layer "F.SilkS")
		)
		(fp_line
			(start 0.105328 0.201008)
			(end 0.105328 -0.198992)
			(stroke
				(width 0.1)
				(type solid)
			)
			(layer "F.SilkS")
		)
		(fp_line
			(start -0.094672 0.001008)
			(end -0.24 0.001008)
			(stroke
				(width 0.1)
				(type solid)
			)
			(layer "F.SilkS")
		)
		(fp_line
			(start -0.094672 0.001008)
			(end 0.105328 -0.198992)
			(stroke
				(width 0.1)
				(type solid)
			)
			(layer "F.SilkS")
		)
		(fp_line
			(start 0.105328 0.001008)
			(end 0.24 0.001)
			(stroke
				(width 0.1)
				(type solid)
			)
			(layer "F.SilkS")
		)
		(fp_line
			(start -1.18 -0.319)
			(end -1.18 0.321)
			(stroke
				(width 0.15)
				(type solid)
			)
			(layer "F.SilkS")
		)
		(fp_line
			(start 0.22 -0.35)
			(end -0.22 -0.35)
			(stroke
				(width 0.15)
				(type solid)
			)
			(layer "F.SilkS")
		)
		(fp_rect
			(start 1.25 0.65)
			(end -1.25 -0.65)
			(stroke
				(width 0.05)
				(type solid)
			)
			(fill none)
			(layer "F.CrtYd")
		)
		(fp_line
			(start -0.199 0.2)
			(end -0.199 0.1)
			(stroke
				(width 0.15)
				(type solid)
			)
			(layer "F.Fab")
		)
		(fp_line
			(start 0.201 0.2)
			(end 0.201 0)
			(stroke
				(width 0.15)
				(type solid)
			)
			(layer "F.Fab")
		)
		(fp_line
			(start -0.199 0)
			(end -0.597 0)
			(stroke
				(width 0.15)
				(type solid)
			)
			(layer "F.Fab")
		)
		(fp_line
			(start -0.101 0)
			(end 0.201 0.2)
			(stroke
				(width 0.15)
				(type solid)
			)
			(layer "F.Fab")
		)
		(fp_line
			(start 0.201 0)
			(end 0.201 -0.202)
			(stroke
				(width 0.15)
				(type solid)
			)
			(layer "F.Fab")
		)
		(fp_line
			(start 0.599 0)
			(end 0.201 0)
			(stroke
				(width 0.15)
				(type solid)
			)
			(layer "F.Fab")
		)
		(fp_line
			(start -0.199 -0.202)
			(end -0.199 0.1)
			(stroke
				(width 0.15)
				(type solid)
			)
			(layer "F.Fab")
		)
		(fp_line
			(start 0.201 -0.202)
			(end -0.101 0)
			(stroke
				(width 0.15)
				(type solid)
			)
			(layer "F.Fab")
		)
		(fp_rect
			(start 0.848 0.4)
			(end -0.85 -0.402)
			(stroke
				(width 0.15)
				(type solid)
			)
			(fill none)
			(layer "F.Fab")
		)
		(fp_text user "License: Apache-2.0"
			(at -1.4224 3.599 90)
			(layer "F.Fab")
			(hide yes)
			(effects
				(font
					(size 0.7 0.7)
					(thickness 0.15)
				)
				(justify right bottom)
			)
		)
		(fp_text user "Author: Antmicro"
			(at -1.4224 4.799 90)
			(layer "F.Fab")
			(hide yes)
			(effects
				(font
					(size 0.7 0.7)
					(thickness 0.15)
				)
				(justify right bottom)
			)
		)
		(fp_text user "${REFERENCE}"
			(at -1.4224 5.999 90)
			(layer "F.Fab")
			(hide yes)
			(effects
				(font
					(size 0.7 0.7)
					(thickness 0.15)
				)
				(justify right bottom)
			)
		)
		(pad "1" smd roundrect
			(at -0.7 0 90)
			(size 0.8 1)
			(layers "F.Cu" "F.Paste" "F.Mask")
			(roundrect_rratio 0.2)
			(net 181 "Net-(D27-C)")
			(pinfunction "C")
			(pintype "passive")
		)
		(pad "2" smd roundrect
			(at 0.7 0 90)
			(size 0.8 1)
			(layers "F.Cu" "F.Paste" "F.Mask")
			(roundrect_rratio 0.2)
			(net 182 "Net-(D27-A)")
			(pinfunction "A")
			(pintype "passive")
		)
	)
	(footprint "antmicro-footprints:C_Pol_EIA-X"
		(layer "F.Cu")
		(at 63.505 88.43)
		(property "Reference" "C2"
			(at -5.135 -2.26 0)
			(layer "F.SilkS")
			(effects
				(font
					(size 0.7 0.7)
					(thickness 0.15)
				)
				(justify left bottom)
			)
		)
		(property "Value" "C_Pol_100u_25V_KEMET-T521-D-107"
			(at 0 3.3 0)
			(layer "F.Fab")
			(effects
				(font
					(size 0.7 0.7)
					(thickness 0.15)
				)
				(justify left bottom)
			)
		)
		(property "Footprint" "antmicro-footprints:C_Pol_EIA-X"
			(at 0 0 0)
			(layer "F.Fab")
			(hide yes)
			(effects
				(font
					(size 1.27 1.27)
					(thickness 0.15)
				)
			)
		)
		(property "Datasheet" "https://content.kemet.com/datasheets/KEM_T2076_T52X-530.pdf"
			(at 0 0 0)
			(layer "F.Fab")
			(hide yes)
			(effects
				(font
					(size 1.27 1.27)
					(thickness 0.15)
				)
			)
		)
		(property "Description" "Surface Mount Tantalum Capacitor, 100 µF, 25 V, 2917 [7343 Metric], ± 20%, 0.04 ohm"
			(at 0 0 0)
			(layer "F.Fab")
			(hide yes)
			(effects
				(font
					(size 1.27 1.27)
					(thickness 0.15)
				)
			)
		)
		(property "Val" "100u"
			(at 0 0 0)
			(unlocked yes)
			(layer "F.Fab")
			(hide yes)
			(effects
				(font
					(size 1 1)
					(thickness 0.15)
				)
			)
		)
		(property "MPN" "T521D107M025ATE040"
			(at 0 0 0)
			(unlocked yes)
			(layer "F.Fab")
			(hide yes)
			(effects
				(font
					(size 1 1)
					(thickness 0.15)
				)
			)
		)
		(property "Manufacturer" "KEMET"
			(at 0 0 0)
			(unlocked yes)
			(layer "F.Fab")
			(hide yes)
			(effects
				(font
					(size 1 1)
					(thickness 0.15)
				)
			)
		)
		(property "License" "Apache-2.0"
			(at 0 0 0)
			(unlocked yes)
			(layer "F.Fab")
			(hide yes)
			(effects
				(font
					(size 1 1)
					(thickness 0.15)
				)
			)
		)
		(property "Author" "Antmicro"
			(at 0 0 0)
			(unlocked yes)
			(layer "F.Fab")
			(hide yes)
			(effects
				(font
					(size 1 1)
					(thickness 0.15)
				)
			)
		)
		(property "Voltage" "25V"
			(at 0 0 0)
			(unlocked yes)
			(layer "F.Fab")
			(hide yes)
			(effects
				(font
					(size 1 1)
					(thickness 0.15)
				)
			)
		)
		(property "Dielectric" "template_dielectric"
			(at 0 0 0)
			(unlocked yes)
			(layer "F.Fab")
			(hide yes)
			(effects
				(font
					(size 1 1)
					(thickness 0.15)
				)
			)
		)
		(sheetname "SoM")
		(sheetfile "som.kicad_sch")
		(attr smd)
		(fp_line
			(start -4.5 -1.8)
			(end -4 -1.8)
			(stroke
				(width 0.15)
				(type solid)
			)
			(layer "F.SilkS")
		)
		(fp_line
			(start -4.25 -2.05)
			(end -4.25 -1.551)
			(stroke
				(width 0.15)
				(type solid)
			)
			(layer "F.SilkS")
		)
		(fp_line
			(start -3.6 -2.2)
			(end 3.6 -2.2)
			(stroke
				(width 0.15)
				(type solid)
			)
			(layer "F.SilkS")
		)
		(fp_line
			(start -3.6 -1.44)
			(end -3.6 -2.2)
			(stroke
				(width 0.15)
				(type solid)
			)
			(layer "F.SilkS")
		)
		(fp_line
			(start -3.6 2.2)
			(end -3.6 1.44)
			(stroke
				(width 0.15)
				(type solid)
			)
			(layer "F.SilkS")
		)
		(fp_line
			(start -3.6 2.2)
			(end 3.6 2.2)
			(stroke
				(width 0.15)
				(type solid)
			)
			(layer "F.SilkS")
		)
		(fp_line
			(start 3.6 -1.44)
			(end 3.6 -2.2)
			(stroke
				(width 0.15)
				(type solid)
			)
			(layer "F.SilkS")
		)
		(fp_line
			(start 3.6 2.2)
			(end 3.6 1.44)
			(stroke
				(width 0.15)
				(type solid)
			)
			(layer "F.SilkS")
		)
		(fp_line
			(start -4.7 -1.4)
			(end -4.7 1.45)
			(stroke
				(width 0.05)
				(type solid)
			)
			(layer "F.CrtYd")
		)
		(fp_line
			(start -4.7 -1.4)
			(end -3.75 -1.4)
			(stroke
				(width 0.05)
				(type solid)
			)
			(layer "F.CrtYd")
		)
		(fp_line
			(start -3.75 -2.4)
			(end -3.75 -1.4)
			(stroke
				(width 0.05)
				(type solid)
			)
			(layer "F.CrtYd")
		)
		(fp_line
			(start -3.75 -2.4)
			(end 3.8 -2.4)
			(stroke
				(width 0.05)
				(type solid)
			)
			(layer "F.CrtYd")
		)
		(fp_line
			(start -3.75 1.45)
			(end -4.7 1.45)
			(stroke
				(width 0.05)
				(type solid)
			)
			(layer "F.CrtYd")
		)
		(fp_line
			(start -3.75 1.45)
			(end -3.75 2.4)
			(stroke
				(width 0.05)
				(type solid)
			)
			(layer "F.CrtYd")
		)
		(fp_line
			(start -3.75 2.4)
			(end 3.8 2.4)
			(stroke
				(width 0.05)
				(type solid)
			)
			(layer "F.CrtYd")
		)
		(fp_line
			(start 3.8 -1.45)
			(end 3.8 -2.4)
			(stroke
				(width 0.05)
				(type solid)
			)
			(layer "F.CrtYd")
		)
		(fp_line
			(start 3.8 -1.45)
			(end 4.75 -1.45)
			(stroke
				(width 0.05)
				(type solid)
			)
			(layer "F.CrtYd")
		)
		(fp_line
			(start 3.8 2.4)
			(end 3.8 1.4)
			(stroke
				(width 0.05)
				(type solid)
			)
			(layer "F.CrtYd")
		)
		(fp_line
			(start 4.75 1.4)
			(end 3.8 1.4)
			(stroke
				(width 0.05)
				(type solid)
			)
			(layer "F.CrtYd")
		)
		(fp_line
			(start 4.75 1.4)
			(end 4.75 -1.45)
			(stroke
				(width 0.05)
				(type solid)
			)
			(layer "F.CrtYd")
		)
		(fp_line
			(start -3.799 -2.3)
			(end 3.799 -2.3)
			(stroke
				(width 0.15)
				(type solid)
			)
			(layer "F.Fab")
		)
		(fp_line
			(start -3.799 2.3)
			(end -3.799 -2.3)
			(stroke
				(width 0.15)
				(type solid)
			)
			(layer "F.Fab")
		)
		(fp_line
			(start 3.799 -2.3)
			(end 3.799 2.3)
			(stroke
				(width 0.15)
				(type solid)
			)
			(layer "F.Fab")
		)
		(fp_line
			(start 3.799 2.3)
			(end -3.799 2.3)
			(stroke
				(width 0.15)
				(type solid)
			)
			(layer "F.Fab")
		)
		(fp_text user "License: Apache-2.0"
			(at -4.5 6.79 0)
			(layer "F.Fab")
			(hide yes)
			(effects
				(font
					(size 0.7 0.7)
					(thickness 0.15)
				)
				(justify left bottom)
			)
		)
		(fp_text user "${REFERENCE}"
			(at -4.5 4.39 0)
			(layer "F.Fab")
			(hide yes)
			(effects
				(font
					(size 0.7 0.7)
					(thickness 0.15)
				)
				(justify left bottom)
			)
		)
		(fp_text user "Author: Antmicro"
			(at -4.5 5.59 0)
			(layer "F.Fab")
			(hide yes)
			(effects
				(font
					(size 0.7 0.7)
					(thickness 0.15)
				)
				(justify left bottom)
			)
		)
		(pad "1" smd roundrect
			(at -3.25 0)
			(size 2.5 2.33)
			(layers "F.Cu" "F.Paste" "F.Mask")
			(roundrect_rratio 0.1)
			(net 438 "/SoM/SoM_VIN")
			(pintype "passive")
		)
		(pad "2" smd roundrect
			(at 3.25 0)
			(size 2.5 2.33)
			(layers "F.Cu" "F.Paste" "F.Mask")
			(roundrect_rratio 0.1)
			(net 1 "GND")
			(pintype "passive")
		)
	)
	(footprint "antmicro-footprints:R_Array_4x0402"
		(layer "F.Cu")
		(at 139.3 102.3 90)
		(property "Reference" "R54"
			(at -1.025 -0.95 90)
			(layer "F.SilkS")
			(effects
				(font
					(size 0.7 0.7)
					(thickness 0.15)
				)
				(justify left bottom)
			)
		)
		(property "Value" "R_4x330R_0402_array"
			(at -1.5 2 90)
			(layer "F.Fab")
			(effects
				(font
					(size 0.7 0.7)
					(thickness 0.15)
				)
				(justify left bottom)
			)
		)
		(property "Footprint" "antmicro-footprints:R_Array_4x0402"
			(at 0 0 90)
			(layer "F.Fab")
			(hide yes)
			(effects
				(font
					(size 1.27 1.27)
					(thickness 0.15)
				)
			)
		)
		(property "Datasheet" "http://industrial.panasonic.com/cdbs/www-data/pdf/AOC0000/AOC0000C14.pdf"
			(at 0 0 90)
			(layer "F.Fab")
			(hide yes)
			(effects
				(font
					(size 1.27 1.27)
					(thickness 0.15)
				)
			)
		)
		(property "Author" "Antmicro"
			(at 241.6 -37 0)
			(layer "F.Fab")
			(hide yes)
			(effects
				(font
					(size 1 1)
					(thickness 0.15)
				)
			)
		)
		(property "License" "Apache-2.0"
			(at 241.6 -37 0)
			(layer "F.Fab")
			(hide yes)
			(effects
				(font
					(size 1 1)
					(thickness 0.15)
				)
			)
		)
		(property "MPN" "EXB-28V331JX"
			(at 241.6 -37 0)
			(layer "F.Fab")
			(hide yes)
			(effects
				(font
					(size 1 1)
					(thickness 0.15)
				)
			)
		)
		(property "Manufacturer" "Panasonic"
			(at 241.6 -37 0)
			(layer "F.Fab")
			(hide yes)
			(effects
				(font
					(size 1 1)
					(thickness 0.15)
				)
			)
		)
		(property "Val" "R_4x330R_0402"
			(at 241.6 -37 0)
			(layer "F.Fab")
			(hide yes)
			(effects
				(font
					(size 1 1)
					(thickness 0.15)
				)
			)
		)
		(sheetname "Peripherals")
		(sheetfile "peripherals.kicad_sch")
		(attr smd)
		(fp_line
			(start -1.17 -0.5)
			(end -1.17 0.498)
			(stroke
				(width 0.15)
				(type solid)
			)
			(layer "F.SilkS")
		)
		(fp_line
			(start 1.167 0.498)
			(end 1.167 -0.5)
			(stroke
				(width 0.15)
				(type solid)
			)
			(layer "F.SilkS")
		)
		(fp_rect
			(start -1.2 -0.9)
			(end 1.2 0.9)
			(stroke
				(width 0.05)
				(type solid)
			)
			(fill none)
			(layer "F.CrtYd")
		)
		(fp_line
			(start 0.998 -0.5)
			(end 0.998 0.498)
			(stroke
				(width 0.15)
				(type solid)
			)
			(layer "F.Fab")
		)
		(fp_line
			(start -1 -0.5)
			(end 0.998 -0.5)
			(stroke
				(width 0.15)
				(type solid)
			)
			(layer "F.Fab")
		)
		(fp_line
			(start 0.998 0.498)
			(end -1 0.498)
			(stroke
				(width 0.15)
				(type solid)
			)
			(layer "F.Fab")
		)
		(fp_line
			(start -1 0.498)
			(end -1 -0.5)
			(stroke
				(width 0.15)
				(type solid)
			)
			(layer "F.Fab")
		)
		(fp_text user "${REFERENCE}"
			(at -1.5 3.25 90)
			(layer "F.Fab")
			(hide yes)
			(effects
				(font
					(size 0.7 0.7)
					(thickness 0.15)
				)
				(justify left bottom)
			)
		)
		(fp_text user "Author: Antmicro"
			(at -1.5 4.5 90)
			(layer "F.Fab")
			(hide yes)
			(effects
				(font
					(size 0.7 0.7)
					(thickness 0.15)
				)
				(justify left bottom)
			)
		)
		(fp_text user "License: Apache-2.0"
			(at -1.5 5.75 90)
			(layer "F.Fab")
			(hide yes)
			(effects
				(font
					(size 0.7 0.7)
					(thickness 0.15)
				)
				(justify left bottom)
			)
		)
		(pad "1" smd roundrect
			(at -0.802 0.45 90)
			(size 0.4 0.5)
			(layers "F.Cu" "F.Paste" "F.Mask")
			(roundrect_rratio 0.25)
			(net 591 "/Peripherals/SPIO_MOSI_CONN")
			(pinfunction "R1.1")
			(pintype "passive")
		)
		(pad "2" smd roundrect
			(at -0.272 0.45 90)
			(size 0.4 0.5)
			(layers "F.Cu" "F.Paste" "F.Mask")
			(roundrect_rratio 0.25)
			(net 589 "/Peripherals/SPIO_SCK_CONN")
			(pinfunction "R2.1")
			(pintype "passive")
		)
		(pad "3" smd roundrect
			(at 0.27 0.45 90)
			(size 0.4 0.5)
			(layers "F.Cu" "F.Paste" "F.Mask")
			(roundrect_rratio 0.25)
			(net 587 "/Peripherals/I2S0_LRCK_CONN")
			(pinfunction "R3.1")
			(pintype "passive")
		)
		(pad "4" smd roundrect
			(at 0.8 0.45 90)
			(size 0.4 0.5)
			(layers "F.Cu" "F.Paste" "F.Mask")
			(roundrect_rratio 0.25)
			(net 585 "/Peripherals/I2S0_SDIN_CONN")
			(pinfunction "R4.1")
			(pintype "passive")
		)
		(pad "5" smd roundrect
			(at 0.8 -0.452 90)
			(size 0.4 0.5)
			(layers "F.Cu" "F.Paste" "F.Mask")
			(roundrect_rratio 0.25)
			(net 71 "I2S0_SDIN")
			(pinfunction "R4.2")
			(pintype "passive")
		)
		(pad "6" smd roundrect
			(at 0.27 -0.452 90)
			(size 0.4 0.5)
			(layers "F.Cu" "F.Paste" "F.Mask")
			(roundrect_rratio 0.25)
			(net 73 "I2S0_LRCK")
			(pinfunction "R3.2")
			(pintype "passive")
		)
		(pad "7" smd roundrect
			(at -0.272 -0.452 90)
			(size 0.4 0.5)
			(layers "F.Cu" "F.Paste" "F.Mask")
			(roundrect_rratio 0.25)
			(net 31 "SPIO_SCK")
			(pinfunction "R2.2")
			(pintype "passive")
		)
		(pad "8" smd roundrect
			(at -0.802 -0.452 90)
			(size 0.4 0.5)
			(layers "F.Cu" "F.Paste" "F.Mask")
			(roundrect_rratio 0.25)
			(net 30 "SPIO_MOSI")
			(pinfunction "R1.2")
			(pintype "passive")
		)
	)
)
